(kicad_pcb
	(version 20260206)
	(generator "pcbnew")
	(generator_version "10.0")
	(general
		(thickness 1.6)
		(legacy_teardrops no)
	)
	(paper "A4")
	(title_block
		(title "baseboard — 13948-1b.1110WZS1818.brd")
		(comment 1 "Honey Badger (Wiwynn) / footprints 874-880 of 2523")
	)
	(layers
		(0 "F.Cu" signal "TOP")
		(4 "In1.Cu" signal "L2GND")
		(6 "In2.Cu" signal "L3")
		(8 "In3.Cu" signal "L4VCC")
		(10 "In4.Cu" signal "L5VCC")
		(12 "In5.Cu" signal "L6")
		(14 "In6.Cu" signal "L7GND")
		(2 "B.Cu" signal "BOTTOM")
		(9 "F.Adhes" user "F.Adhesive")
		(11 "B.Adhes" user "B.Adhesive")
		(13 "F.Paste" user "Package Geometry/Pastemask Top")
		(15 "B.Paste" user "Package Geometry/Pastemask Bottom")
		(5 "F.SilkS" user "Ref Des/Silkscreen Top")
		(7 "B.SilkS" user "Ref Des/Silkscreen Bottom")
		(1 "F.Mask" user "Board Geometry/Soldermask Top")
		(3 "B.Mask" user "Board Geometry/Soldermask Bottom")
		(17 "Dwgs.User" user "User.Drawings")
		(19 "Cmts.User" user "User.Comments")
		(21 "Eco1.User" user "User.Eco1")
		(23 "Eco2.User" user "User.Eco2")
		(25 "Edge.Cuts" user "Board Geometry/Outline")
		(27 "Margin" user)
		(31 "F.CrtYd" user "Package Geometry/Place Bound Top")
		(29 "B.CrtYd" user "Package Geometry/Place Bound Bottom")
		(35 "F.Fab" user "Ref Des/Assembly Top")
		(33 "B.Fab" user "Ref Des/Assembly Bottom")
	)
	(footprint ""
		(layer "F.Cu")
		(at 84.582 -24.384 180)
		(property "Reference" "PR188"
			(at 0 0 180)
			(layer "F.SilkS")
			(hide yes)
			(effects
				(font
					(size 1.27 1.27)
				)
			)
		)
		(property "Value" "100KR2F-L1-GP"
			(at 0.064008 -3.993896 180)
			(unlocked yes)
			(layer "F.Fab")
			(hide yes)
			(effects
				(font
					(size 1.016 1.016)
					(thickness 0.1524)
				)
			)
		)
		(property "Device Type" "R402H16"
			(at 0.064008 -5.517896 180)
			(unlocked yes)
			(layer "F.Fab")
			(hide yes)
			(effects
				(font
					(size 1.016 1.016)
					(thickness 0.1524)
				)
			)
		)
		(duplicate_pad_numbers_are_jumpers no)
		(fp_line
			(start 0.508 -0.9398)
			(end -0.508 -0.9398)
			(stroke
				(width 0.1524)
				(type default)
			)
			(layer "F.SilkS")
		)
		(fp_line
			(start -0.508 -0.9398)
			(end -0.508 0.9398)
			(stroke
				(width 0.1524)
				(type default)
			)
			(layer "F.SilkS")
		)
		(fp_rect
			(start -0.508 0.9398)
			(end 0.508 -0.9398)
			(stroke
				(width 0)
				(type default)
			)
			(fill no)
			(layer "F.CrtYd")
		)
		(fp_rect
			(start -0.508 0.9398)
			(end 0.508 -0.9398)
			(stroke
				(width 0)
				(type default)
			)
			(fill no)
			(layer "F.Fab")
		)
		(pad "1" smd custom
			(at 0 -0.4445 180)
			(size 0.1397 0.1397)
			(layers "F.Cu" "F.Mask" "F.Paste")
			(net "VT235_VDES")
			(options
				(clearance outline)
				(anchor circle)
			)
			(primitives
				(gr_poly
					(pts
						(arc
							(start -0.1778 -0.2794)
							(mid -0.249642 -0.249642)
							(end -0.2794 -0.1778)
						)
						(arc
							(start -0.2794 0.1778)
							(mid -0.249642 0.249642)
							(end -0.1778 0.2794)
						)
						(arc
							(start 0.1778 0.2794)
							(mid 0.249642 0.249642)
							(end 0.2794 0.1778)
						)
						(arc
							(start 0.2794 -0.1778)
							(mid 0.249642 -0.249642)
							(end 0.1778 -0.2794)
						)
					)
					(width 0)
					(fill yes)
				)
			)
		)
		(pad "2" smd custom
			(at 0 0.4445 180)
			(size 0.1397 0.1397)
			(layers "F.Cu" "F.Mask" "F.Paste")
			(net "VT235_VREF")
			(options
				(clearance outline)
				(anchor circle)
			)
			(primitives
				(gr_poly
					(pts
						(arc
							(start -0.1778 -0.2794)
							(mid -0.249642 -0.249642)
							(end -0.2794 -0.1778)
						)
						(arc
							(start -0.2794 0.1778)
							(mid -0.249642 0.249642)
							(end -0.1778 0.2794)
						)
						(arc
							(start 0.1778 0.2794)
							(mid 0.249642 0.249642)
							(end 0.2794 0.1778)
						)
						(arc
							(start 0.2794 -0.1778)
							(mid 0.249642 -0.249642)
							(end 0.1778 -0.2794)
						)
					)
					(width 0)
					(fill yes)
				)
			)
		)
	)
	(footprint ""
		(layer "F.Cu")
		(at 86.49716 -37.973 -90)
		(property "Reference" "SC885"
			(at 0 0 270)
			(layer "F.SilkS")
			(hide yes)
			(effects
				(font
					(size 1.27 1.27)
				)
			)
		)
		(property "Value" "SCD01U10V1KX-GP"
			(at -2.8321 -1.7399 270)
			(unlocked yes)
			(layer "F.Fab")
			(hide yes)
			(effects
				(font
					(size 1.016 1.016)
					(thickness 0.1524)
				)
			)
		)
		(property "Device Type" "C0201H13"
			(at -2.8321 -3.2639 270)
			(unlocked yes)
			(layer "F.Fab")
			(hide yes)
			(effects
				(font
					(size 1.016 1.016)
					(thickness 0.1524)
				)
			)
		)
		(duplicate_pad_numbers_are_jumpers no)
		(fp_rect
			(start -0.2794 0.6477)
			(end 0.2794 -0.6477)
			(stroke
				(width 0)
				(type default)
			)
			(fill no)
			(layer "F.CrtYd")
		)
		(fp_rect
			(start -0.2794 0.6477)
			(end 0.2794 -0.6477)
			(stroke
				(width 0)
				(type default)
			)
			(fill no)
			(layer "F.Fab")
		)
		(pad "1" smd custom
			(at 0 -0.2794 270)
			(size 0.0762 0.0762)
			(layers "F.Cu" "F.Mask" "F.Paste")
			(net "SAS3008_RAID_TX_C_N3")
			(options
				(clearance outline)
				(anchor circle)
			)
			(primitives
				(gr_poly
					(pts
						(arc
							(start 0.1524 -0.127)
							(mid 0.137521 -0.162921)
							(end 0.1016 -0.1778)
						)
						(arc
							(start -0.1016 -0.1778)
							(mid -0.137521 -0.162921)
							(end -0.1524 -0.127)
						)
						(arc
							(start -0.1524 0.127)
							(mid -0.137521 0.162921)
							(end -0.1016 0.1778)
						)
						(arc
							(start 0.1016 0.1778)
							(mid 0.137521 0.162921)
							(end 0.1524 0.127)
						)
					)
					(width 0)
					(fill yes)
				)
			)
		)
		(pad "2" smd custom
			(at 0 0.2794 270)
			(size 0.0762 0.0762)
			(layers "F.Cu" "F.Mask" "F.Paste")
			(net "SAS3008_RAID_TX_N3")
			(options
				(clearance outline)
				(anchor circle)
			)
			(primitives
				(gr_poly
					(pts
						(arc
							(start 0.1524 -0.127)
							(mid 0.137521 -0.162921)
							(end 0.1016 -0.1778)
						)
						(arc
							(start -0.1016 -0.1778)
							(mid -0.137521 -0.162921)
							(end -0.1524 -0.127)
						)
						(arc
							(start -0.1524 0.127)
							(mid -0.137521 0.162921)
							(end -0.1016 0.1778)
						)
						(arc
							(start 0.1016 0.1778)
							(mid 0.137521 0.162921)
							(end 0.1524 0.127)
						)
					)
					(width 0)
					(fill yes)
				)
			)
		)
	)
	(footprint ""
		(layer "F.Cu")
		(at 219.72397 -69.088)
		(property "Reference" "R15"
			(at 0 0 0)
			(layer "F.SilkS")
			(hide yes)
			(effects
				(font
					(size 1.27 1.27)
				)
			)
		)
		(property "Value" "100R2F-L1-GP-U"
			(at 0.064008 -3.993896 0)
			(unlocked yes)
			(layer "F.Fab")
			(hide yes)
			(effects
				(font
					(size 1.016 1.016)
					(thickness 0.1524)
				)
			)
		)
		(property "Device Type" "R402H14"
			(at 0.064008 -5.517896 0)
			(unlocked yes)
			(layer "F.Fab")
			(hide yes)
			(effects
				(font
					(size 1.016 1.016)
					(thickness 0.1524)
				)
			)
		)
		(duplicate_pad_numbers_are_jumpers no)
		(fp_line
			(start -0.508 -0.9398)
			(end -0.508 0.9398)
			(stroke
				(width 0.1524)
				(type default)
			)
			(layer "F.SilkS")
		)
		(fp_line
			(start 0.508 -0.9398)
			(end -0.508 -0.9398)
			(stroke
				(width 0.1524)
				(type default)
			)
			(layer "F.SilkS")
		)
		(fp_rect
			(start -0.508 0.9398)
			(end 0.508 -0.9398)
			(stroke
				(width 0)
				(type default)
			)
			(fill no)
			(layer "F.CrtYd")
		)
		(fp_rect
			(start -0.508 0.9398)
			(end 0.508 -0.9398)
			(stroke
				(width 0)
				(type default)
			)
			(fill no)
			(layer "F.Fab")
		)
		(pad "1" smd custom
			(at 0 -0.4445)
			(size 0.1397 0.1397)
			(layers "F.Cu" "F.Mask" "F.Paste")
			(net "SVR_ID0")
			(options
				(clearance outline)
				(anchor circle)
			)
			(primitives
				(gr_poly
					(pts
						(arc
							(start -0.1778 -0.2794)
							(mid -0.249642 -0.249642)
							(end -0.2794 -0.1778)
						)
						(arc
							(start -0.2794 0.1778)
							(mid -0.249642 0.249642)
							(end -0.1778 0.2794)
						)
						(arc
							(start 0.1778 0.2794)
							(mid 0.249642 0.249642)
							(end 0.2794 0.1778)
						)
						(arc
							(start 0.2794 -0.1778)
							(mid 0.249642 -0.249642)
							(end 0.1778 -0.2794)
						)
					)
					(width 0)
					(fill yes)
				)
			)
		)
		(pad "2" smd custom
			(at 0 0.4445)
			(size 0.1397 0.1397)
			(layers "F.Cu" "F.Mask" "F.Paste")
			(net "GND")
			(options
				(clearance outline)
				(anchor circle)
			)
			(primitives
				(gr_poly
					(pts
						(arc
							(start -0.1778 -0.2794)
							(mid -0.249642 -0.249642)
							(end -0.2794 -0.1778)
						)
						(arc
							(start -0.2794 0.1778)
							(mid -0.249642 0.249642)
							(end -0.1778 0.2794)
						)
						(arc
							(start 0.1778 0.2794)
							(mid 0.249642 0.249642)
							(end 0.2794 0.1778)
						)
						(arc
							(start 0.2794 -0.1778)
							(mid 0.249642 -0.249642)
							(end 0.1778 -0.2794)
						)
					)
					(width 0)
					(fill yes)
				)
			)
		)
	)
	(footprint ""
		(layer "F.Cu")
		(at 317.754 -118.618 180)
		(property "Reference" "PR29"
			(at 0 0 180)
			(layer "F.SilkS")
			(hide yes)
			(effects
				(font
					(size 1.27 1.27)
				)
			)
		)
		(property "Value" "475KR2F-GP"
			(at 0.064008 -3.993896 180)
			(unlocked yes)
			(layer "F.Fab")
			(hide yes)
			(effects
				(font
					(size 1.016 1.016)
					(thickness 0.1524)
				)
			)
		)
		(property "Device Type" "R402H16"
			(at 0.064008 -5.517896 180)
			(unlocked yes)
			(layer "F.Fab")
			(hide yes)
			(effects
				(font
					(size 1.016 1.016)
					(thickness 0.1524)
				)
			)
		)
		(duplicate_pad_numbers_are_jumpers no)
		(fp_line
			(start 0.508 -0.9398)
			(end -0.508 -0.9398)
			(stroke
				(width 0.1524)
				(type default)
			)
			(layer "F.SilkS")
		)
		(fp_line
			(start -0.508 -0.9398)
			(end -0.508 0.9398)
			(stroke
				(width 0.1524)
				(type default)
			)
			(layer "F.SilkS")
		)
		(fp_rect
			(start -0.508 0.9398)
			(end 0.508 -0.9398)
			(stroke
				(width 0)
				(type default)
			)
			(fill no)
			(layer "F.CrtYd")
		)
		(fp_rect
			(start -0.508 0.9398)
			(end 0.508 -0.9398)
			(stroke
				(width 0)
				(type default)
			)
			(fill no)
			(layer "F.Fab")
		)
		(pad "1" smd custom
			(at 0 -0.4445 180)
			(size 0.1397 0.1397)
			(layers "F.Cu" "F.Mask" "F.Paste")
			(net "P3V3_STBY_MODE")
			(options
				(clearance outline)
				(anchor circle)
			)
			(primitives
				(gr_poly
					(pts
						(arc
							(start -0.1778 -0.2794)
							(mid -0.249642 -0.249642)
							(end -0.2794 -0.1778)
						)
						(arc
							(start -0.2794 0.1778)
							(mid -0.249642 0.249642)
							(end -0.1778 0.2794)
						)
						(arc
							(start 0.1778 0.2794)
							(mid 0.249642 0.249642)
							(end 0.2794 0.1778)
						)
						(arc
							(start 0.2794 -0.1778)
							(mid 0.249642 -0.249642)
							(end 0.1778 -0.2794)
						)
					)
					(width 0)
					(fill yes)
				)
			)
		)
		(pad "2" smd custom
			(at 0 0.4445 180)
			(size 0.1397 0.1397)
			(layers "F.Cu" "F.Mask" "F.Paste")
			(net "P3V3_STBY_PG")
			(options
				(clearance outline)
				(anchor circle)
			)
			(primitives
				(gr_poly
					(pts
						(arc
							(start -0.1778 -0.2794)
							(mid -0.249642 -0.249642)
							(end -0.2794 -0.1778)
						)
						(arc
							(start -0.2794 0.1778)
							(mid -0.249642 0.249642)
							(end -0.1778 0.2794)
						)
						(arc
							(start 0.1778 0.2794)
							(mid 0.249642 0.249642)
							(end 0.2794 0.1778)
						)
						(arc
							(start 0.2794 -0.1778)
							(mid 0.249642 -0.249642)
							(end 0.1778 -0.2794)
						)
					)
					(width 0)
					(fill yes)
				)
			)
		)
	)
	(footprint ""
		(layer "F.Cu")
		(at 158.369 -110.998 90)
		(property "Reference" "SC1207"
			(at 0 0 90)
			(layer "F.SilkS")
			(hide yes)
			(effects
				(font
					(size 1.27 1.27)
				)
			)
		)
		(property "Value" "SC10U6D3V5KX-4GP"
			(at -0.0762 -6.1214 90)
			(unlocked yes)
			(layer "F.Fab")
			(hide yes)
			(effects
				(font
					(size 1.016 1.016)
					(thickness 0.1524)
				)
			)
		)
		(property "Device Type" "C805H58"
			(at -0.0762 -8.1534 90)
			(unlocked yes)
			(layer "F.Fab")
			(hide yes)
			(effects
				(font
					(size 1.016 1.016)
					(thickness 0.1524)
				)
			)
		)
		(duplicate_pad_numbers_are_jumpers no)
		(fp_line
			(start 0.635 0)
			(end -0.635 0)
			(stroke
				(width 0.508)
				(type default)
			)
			(layer "F.SilkS")
		)
		(fp_rect
			(start -0.9652 1.778)
			(end 0.9652 -1.778)
			(stroke
				(width 0)
				(type default)
			)
			(fill no)
			(layer "F.CrtYd")
		)
		(fp_poly
			(pts
				(xy -0.9652 -1.778) (xy 0.9652 -1.778) (xy 0.9652 1.778) (xy -0.9652 1.778)
			)
			(stroke
				(width 0)
				(type default)
			)
			(fill no)
			(layer "F.Fab")
		)
		(pad "1" smd rect
			(at 0 -0.9652 90)
			(size 1.397 1.143)
			(layers "F.Cu" "F.Mask" "F.Paste")
			(net "P0V9_E")
		)
		(pad "2" smd rect
			(at 0 0.9652 90)
			(size 1.397 1.143)
			(layers "F.Cu" "F.Mask" "F.Paste")
			(net "GND")
		)
	)
	(footprint ""
		(layer "F.Cu")
		(at 33.50006 -68.460112)
		(property "Reference" "LED7"
			(at 0 0 0)
			(layer "F.SilkS")
			(hide yes)
			(effects
				(font
					(size 1.27 1.27)
				)
			)
		)
		(property "Value" "LED-RB-8-GP"
			(at -4.6736 3.8354 0)
			(unlocked yes)
			(layer "F.Fab")
			(hide yes)
			(effects
				(font
					(size 1.016 1.016)
					(thickness 0.1524)
				)
			)
		)
		(property "Device Type" "LED-100-3P-067106H325"
			(at -4.6736 2.3114 0)
			(unlocked yes)
			(layer "F.Fab")
			(hide yes)
			(effects
				(font
					(size 1.016 1.016)
					(thickness 0.1524)
				)
			)
		)
		(duplicate_pad_numbers_are_jumpers no)
		(fp_line
			(start -3.6068 -0.889)
			(end 3.6068 -0.889)
			(stroke
				(width 0.1524)
				(type default)
			)
			(layer "F.SilkS")
		)
		(fp_line
			(start -3.6068 6.6548)
			(end -3.6068 -0.889)
			(stroke
				(width 0.1524)
				(type default)
			)
			(layer "F.SilkS")
		)
		(fp_line
			(start -1.7526 6.6548)
			(end -3.6068 6.6548)
			(stroke
				(width 0.1524)
				(type default)
			)
			(layer "F.SilkS")
		)
		(fp_line
			(start -1.7526 10.414)
			(end -1.7526 6.6548)
			(stroke
				(width 0.1524)
				(type default)
			)
			(layer "F.SilkS")
		)
		(fp_line
			(start 1.7526 6.6548)
			(end 1.7526 10.414)
			(stroke
				(width 0.1524)
				(type default)
			)
			(layer "F.SilkS")
		)
		(fp_line
			(start 1.7526 10.414)
			(end -1.7526 10.414)
			(stroke
				(width 0.1524)
				(type default)
			)
			(layer "F.SilkS")
		)
		(fp_line
			(start 3.6068 -0.889)
			(end 3.6068 6.6548)
			(stroke
				(width 0.1524)
				(type default)
			)
			(layer "F.SilkS")
		)
		(fp_line
			(start 3.6068 6.6548)
			(end 1.7526 6.6548)
			(stroke
				(width 0.1524)
				(type default)
			)
			(layer "F.SilkS")
		)
		(fp_circle
			(center -2.54 0)
			(end -1.5494 0)
			(stroke
				(width 0.3048)
				(type default)
			)
			(fill no)
			(layer "F.SilkS")
		)
		(fp_circle
			(center 0 0)
			(end 0.9906 0)
			(stroke
				(width 0.3048)
				(type default)
			)
			(fill no)
			(layer "F.SilkS")
		)
		(fp_circle
			(center 2.54 0)
			(end 3.5306 0)
			(stroke
				(width 0.3048)
				(type default)
			)
			(fill no)
			(layer "F.SilkS")
		)
		(fp_poly
			(pts
				(xy -1.4986 10.1473) (xy -1.4986 6.4008) (xy -3.3528 6.4008) (xy -3.3528 -0.3937) (xy 3.3528 -0.3937)
				(xy 3.3528 6.4008) (xy 1.4986 6.4008) (xy 1.4986 10.1473)
			)
			(stroke
				(width 0)
				(type default)
			)
			(fill no)
			(layer "F.CrtYd")
		)
		(fp_poly
			(pts
				(xy -2.0066 10.668) (xy 2.0066 10.668) (xy 2.0066 6.9088) (xy 3.8608 6.9088) (xy 3.8608 2.2098)
				(xy 3.3528 2.2098) (xy 3.3528 6.4008) (xy 1.4986 6.4008) (xy 1.4986 10.1473) (xy -1.4986 10.1473)
				(xy -1.4986 6.4008) (xy -3.3528 6.4008) (xy -3.3528 -0.3937) (xy 3.3528 -0.3937) (xy 3.3528 2.1971)
				(xy 3.8608 2.1971) (xy 3.8608 -1.143) (xy -3.8608 -1.143) (xy -3.8608 6.9088) (xy -2.0066 6.9088)
			)
			(stroke
				(width 0)
				(type default)
			)
			(fill no)
			(layer "F.CrtYd")
		)
		(fp_poly
			(pts
				(xy -2.0066 10.668) (xy -2.0066 6.9088) (xy -3.8608 6.9088) (xy -3.8608 -1.143) (xy 3.8608 -1.143)
				(xy 3.8608 6.9088) (xy 2.0066 6.9088) (xy 2.0066 10.668)
			)
			(stroke
				(width 0)
				(type default)
			)
			(fill no)
			(layer "F.Fab")
		)
		(pad "1" thru_hole circle
			(at 2.54 0)
			(size 1.27 1.27)
			(drill 0.889)
			(layers "*.Cu" "*.Mask")
			(remove_unused_layers no)
			(net "INTA_LED_BLUE_C")
			(clearance 0.1651)
			(thermal_gap 0.1651)
		)
		(pad "2" thru_hole circle
			(at 0 0)
			(size 1.27 1.27)
			(drill 0.889)
			(layers "*.Cu" "*.Mask")
			(remove_unused_layers no)
			(net "INTA_LED_GND")
			(clearance 0.1651)
			(thermal_gap 0.1651)
		)
		(pad "3" thru_hole circle
			(at -2.54 0)
			(size 1.27 1.27)
			(drill 0.889)
			(layers "*.Cu" "*.Mask")
			(remove_unused_layers no)
			(net "INTA_LED_RED_C")
			(clearance 0.1651)
			(thermal_gap 0.1651)
		)
	)
	(footprint ""
		(layer "F.Cu")
		(at 315.341 -192.278)
		(property "Reference" "TP178"
			(at 0 0 0)
			(layer "F.SilkS")
			(hide yes)
			(effects
				(font
					(size 1.27 1.27)
				)
			)
		)
		(property "Value" "TPAD28"
			(at -0.0127 -1.6637 0)
			(unlocked yes)
			(layer "F.Fab")
			(hide yes)
			(effects
				(font
					(size 1.016 1.016)
					(thickness 0.1524)
				)
			)
		)
		(property "Device Type" "TPAD28"
			(at -0.0127 -3.1877 0)
			(unlocked yes)
			(layer "F.Fab")
			(hide yes)
			(effects
				(font
					(size 1.016 1.016)
					(thickness 0.1524)
				)
			)
		)
		(duplicate_pad_numbers_are_jumpers no)
		(fp_poly
			(pts
				(arc
					(start 0.3556 0)
					(mid -0.3556 0)
					(end 0.3556 0)
				)
			)
			(stroke
				(width 0)
				(type default)
			)
			(fill no)
			(layer "F.CrtYd")
		)
		(fp_poly
			(pts
				(arc
					(start 0.6096 0)
					(mid -0.6096 0)
					(end 0.6096 0)
				)
			)
			(stroke
				(width 0)
				(type default)
			)
			(fill no)
			(layer "F.Fab")
		)
		(pad "1" smd circle
			(at 0 0)
			(size 0.7112 0.7112)
			(layers "F.Cu" "F.Mask" "F.Paste")
			(net "JTAG_BMC_TCK")
		)
	)
)
